(kicad_pcb
	(version 20260206)
	(generator "pcbnew")
	(generator_version "10.0")
	(general
		(thickness 1.6)
		(legacy_teardrops no)
	)
	(paper "A4")
	(title_block
		(title "01162023_DA0F0TEBIF0_F0T_Expander_BD_F_brd_V02_OCP.brd")
		(comment 1 "Grand Teton / footprints 4382-4387 of 9728")
	)
	(layers
		(0 "F.Cu" signal "TOP")
		(4 "In1.Cu" signal "GND")
		(6 "In2.Cu" signal "VCC")
		(8 "In3.Cu" signal "VCC1")
		(10 "In4.Cu" signal "GND1")
		(12 "In5.Cu" signal "IN1")
		(14 "In6.Cu" signal "GND2")
		(16 "In7.Cu" signal "IN2")
		(18 "In8.Cu" signal "GND3")
		(20 "In9.Cu" signal "IN3")
		(22 "In10.Cu" signal "GND4")
		(24 "In11.Cu" signal "IN4")
		(26 "In12.Cu" signal "GND5")
		(28 "In13.Cu" signal "IN5")
		(30 "In14.Cu" signal "GND6")
		(32 "In15.Cu" signal "IN6")
		(34 "In16.Cu" signal "GND7")
		(2 "B.Cu" signal "BOTTOM")
		(9 "F.Adhes" user "F.Adhesive")
		(11 "B.Adhes" user "B.Adhesive")
		(13 "F.Paste" user "Package Geometry/Pastemask Top")
		(15 "B.Paste" user "Package Geometry/Pastemask Bottom")
		(5 "F.SilkS" user "Ref Des/Silkscreen Top")
		(7 "B.SilkS" user "Ref Des/Silkscreen Bottom")
		(1 "F.Mask" user "Board Geometry/Soldermask Top")
		(3 "B.Mask" user "Board Geometry/Soldermask Bottom")
		(17 "Dwgs.User" user "User.Drawings")
		(19 "Cmts.User" user "User.Comments")
		(21 "Eco1.User" user "User.Eco1")
		(23 "Eco2.User" user "User.Eco2")
		(25 "Edge.Cuts" user "Board Geometry/Outline")
		(27 "Margin" user)
		(31 "F.CrtYd" user "Package Geometry/Place Bound Top")
		(29 "B.CrtYd" user "Package Geometry/Place Bound Bottom")
		(35 "F.Fab" user "Ref Des/Assembly Top")
		(33 "B.Fab" user "Ref Des/Assembly Bottom")
	)
	(footprint ""
		(layer "F.Cu")
		(at 447.275712 -122.525028)
		(property "Reference" "PC492"
			(at 0 0 0)
			(layer "F.SilkS")
			(hide yes)
			(effects
				(font
					(size 1.27 1.27)
				)
			)
		)
		(property "Value" ""
			(at 0 0 0)
			(layer "F.Fab")
			(effects
				(font
					(size 1.27 1.27)
				)
			)
		)
		(duplicate_pad_numbers_are_jumpers no)
		(fp_line
			(start -0.7874 -0.4064)
			(end 0.7874 -0.4064)
			(stroke
				(width 0.1524)
				(type default)
			)
			(layer "F.SilkS")
		)
		(fp_line
			(start -0.7874 0.4064)
			(end -0.7874 -0.4064)
			(stroke
				(width 0.1524)
				(type default)
			)
			(layer "F.SilkS")
		)
		(fp_line
			(start 0.7874 -0.4064)
			(end 0.7874 0.4064)
			(stroke
				(width 0.1524)
				(type default)
			)
			(layer "F.SilkS")
		)
		(fp_line
			(start 0.7874 0.4064)
			(end -0.7874 0.4064)
			(stroke
				(width 0.1524)
				(type default)
			)
			(layer "F.SilkS")
		)
		(fp_line
			(start -0.67945 -0.305054)
			(end -0.12065 -0.305054)
			(stroke
				(width 0.1)
				(type default)
			)
			(layer "F.Fab")
		)
		(fp_line
			(start -0.67945 0.3048)
			(end -0.67945 -0.305054)
			(stroke
				(width 0.1)
				(type default)
			)
			(layer "F.Fab")
		)
		(fp_line
			(start -0.12065 -0.305054)
			(end -0.12065 -0.2794)
			(stroke
				(width 0.1)
				(type default)
			)
			(layer "F.Fab")
		)
		(fp_line
			(start -0.12065 -0.2794)
			(end 0.12065 -0.2794)
			(stroke
				(width 0.1)
				(type default)
			)
			(layer "F.Fab")
		)
		(fp_line
			(start -0.12065 0.2794)
			(end -0.12065 0.3048)
			(stroke
				(width 0.1)
				(type default)
			)
			(layer "F.Fab")
		)
		(fp_line
			(start -0.12065 0.3048)
			(end -0.67945 0.3048)
			(stroke
				(width 0.1)
				(type default)
			)
			(layer "F.Fab")
		)
		(fp_line
			(start 0.120396 0.2794)
			(end -0.12065 0.2794)
			(stroke
				(width 0.1)
				(type default)
			)
			(layer "F.Fab")
		)
		(fp_line
			(start 0.120396 0.3048)
			(end 0.120396 0.2794)
			(stroke
				(width 0.1)
				(type default)
			)
			(layer "F.Fab")
		)
		(fp_line
			(start 0.12065 -0.3048)
			(end 0.67945 -0.3048)
			(stroke
				(width 0.1)
				(type default)
			)
			(layer "F.Fab")
		)
		(fp_line
			(start 0.12065 -0.2794)
			(end 0.12065 -0.3048)
			(stroke
				(width 0.1)
				(type default)
			)
			(layer "F.Fab")
		)
		(fp_line
			(start 0.67945 -0.3048)
			(end 0.67945 0.3048)
			(stroke
				(width 0.1)
				(type default)
			)
			(layer "F.Fab")
		)
		(fp_line
			(start 0.67945 0.3048)
			(end 0.120396 0.3048)
			(stroke
				(width 0.1)
				(type default)
			)
			(layer "F.Fab")
		)
		(pad "1" smd circle
			(at -0.40005 0)
			(size 0 0)
			(layers "F.Cu" "F.Mask" "F.Paste")
			(net "P5V_AUX")
		)
		(pad "2" smd circle
			(at 0.40005 0)
			(size 0 0)
			(layers "F.Cu" "F.Mask" "F.Paste")
			(net "GND")
		)
	)
	(footprint ""
		(layer "F.Cu")
		(at 29.883608 -61.487812 180)
		(property "Reference" "R5839"
			(at 0 0 180)
			(layer "F.SilkS")
			(hide yes)
			(effects
				(font
					(size 1.27 1.27)
				)
			)
		)
		(property "Value" ""
			(at 0 0 180)
			(layer "F.Fab")
			(effects
				(font
					(size 1.27 1.27)
				)
			)
		)
		(duplicate_pad_numbers_are_jumpers no)
		(fp_line
			(start 0.7874 0.4064)
			(end -0.7874 0.4064)
			(stroke
				(width 0.1524)
				(type default)
			)
			(layer "F.SilkS")
		)
		(fp_line
			(start 0.7874 -0.4064)
			(end 0.7874 0.4064)
			(stroke
				(width 0.1524)
				(type default)
			)
			(layer "F.SilkS")
		)
		(fp_line
			(start -0.7874 0.4064)
			(end -0.7874 -0.4064)
			(stroke
				(width 0.1524)
				(type default)
			)
			(layer "F.SilkS")
		)
		(fp_line
			(start -0.7874 -0.4064)
			(end 0.7874 -0.4064)
			(stroke
				(width 0.1524)
				(type default)
			)
			(layer "F.SilkS")
		)
		(fp_line
			(start 0.67945 0.3048)
			(end 0.120396 0.3048)
			(stroke
				(width 0.1)
				(type default)
			)
			(layer "F.Fab")
		)
		(fp_line
			(start 0.67945 -0.3048)
			(end 0.67945 0.3048)
			(stroke
				(width 0.1)
				(type default)
			)
			(layer "F.Fab")
		)
		(fp_line
			(start 0.12065 -0.2794)
			(end 0.12065 -0.3048)
			(stroke
				(width 0.1)
				(type default)
			)
			(layer "F.Fab")
		)
		(fp_line
			(start 0.12065 -0.3048)
			(end 0.67945 -0.3048)
			(stroke
				(width 0.1)
				(type default)
			)
			(layer "F.Fab")
		)
		(fp_line
			(start 0.120396 0.3048)
			(end 0.120396 0.2794)
			(stroke
				(width 0.1)
				(type default)
			)
			(layer "F.Fab")
		)
		(fp_line
			(start 0.120396 0.2794)
			(end -0.12065 0.2794)
			(stroke
				(width 0.1)
				(type default)
			)
			(layer "F.Fab")
		)
		(fp_line
			(start -0.12065 0.3048)
			(end -0.67945 0.3048)
			(stroke
				(width 0.1)
				(type default)
			)
			(layer "F.Fab")
		)
		(fp_line
			(start -0.12065 0.2794)
			(end -0.12065 0.3048)
			(stroke
				(width 0.1)
				(type default)
			)
			(layer "F.Fab")
		)
		(fp_line
			(start -0.12065 -0.2794)
			(end 0.12065 -0.2794)
			(stroke
				(width 0.1)
				(type default)
			)
			(layer "F.Fab")
		)
		(fp_line
			(start -0.12065 -0.305054)
			(end -0.12065 -0.2794)
			(stroke
				(width 0.1)
				(type default)
			)
			(layer "F.Fab")
		)
		(fp_line
			(start -0.67945 0.3048)
			(end -0.67945 -0.305054)
			(stroke
				(width 0.1)
				(type default)
			)
			(layer "F.Fab")
		)
		(fp_line
			(start -0.67945 -0.305054)
			(end -0.12065 -0.305054)
			(stroke
				(width 0.1)
				(type default)
			)
			(layer "F.Fab")
		)
		(pad "1" smd circle
			(at -0.40005 0 180)
			(size 0 0)
			(layers "F.Cu" "F.Mask" "F.Paste")
			(net "PWRGD_P12V_SSD1_D")
		)
		(pad "2" smd circle
			(at 0.40005 0 180)
			(size 0 0)
			(layers "F.Cu" "F.Mask" "F.Paste")
			(net "PWRGD_P12V_SSD1_R")
		)
	)
	(footprint ""
		(layer "F.Cu")
		(at 306.846986 -54.3941)
		(property "Reference" "PU42"
			(at -1.780794 2.755646 0)
			(unlocked yes)
			(layer "F.SilkS")
			(effects
				(font
					(size 0.7874 0.5842)
					(thickness 0.1524)
				)
				(justify left)
			)
		)
		(property "Value" ""
			(at 0 0 0)
			(layer "F.Fab")
			(effects
				(font
					(size 1.27 1.27)
				)
			)
		)
		(duplicate_pad_numbers_are_jumpers no)
		(fp_line
			(start -1.943608 -1.549908)
			(end 1.943608 -1.549908)
			(stroke
				(width 0.1524)
				(type default)
			)
			(layer "F.SilkS")
		)
		(fp_line
			(start -1.943608 1.549908)
			(end -1.943608 -1.549908)
			(stroke
				(width 0.1524)
				(type default)
			)
			(layer "F.SilkS")
		)
		(fp_line
			(start 1.943608 -1.549908)
			(end 1.943608 1.549908)
			(stroke
				(width 0.1524)
				(type default)
			)
			(layer "F.SilkS")
		)
		(fp_line
			(start 1.943608 1.549908)
			(end -1.943608 1.549908)
			(stroke
				(width 0.1524)
				(type default)
			)
			(layer "F.SilkS")
		)
		(fp_poly
			(pts
				(xy -2.019808 -1.549908) (xy -1.257808 -1.549908) (xy -1.257808 -1.880108) (xy -2.019808 -1.880108)
			)
			(stroke
				(width 0)
				(type default)
			)
			(fill yes)
			(layer "F.SilkS")
		)
		(fp_line
			(start -1.549908 -1.549908)
			(end 1.549908 -1.549908)
			(stroke
				(width 0.1)
				(type default)
			)
			(layer "F.Fab")
		)
		(fp_line
			(start -1.549908 1.549908)
			(end -1.549908 -1.549908)
			(stroke
				(width 0.1)
				(type default)
			)
			(layer "F.Fab")
		)
		(fp_line
			(start 1.549908 -1.549908)
			(end 1.549908 1.549908)
			(stroke
				(width 0.1)
				(type default)
			)
			(layer "F.Fab")
		)
		(fp_line
			(start 1.549908 1.549908)
			(end -1.549908 1.549908)
			(stroke
				(width 0.1)
				(type default)
			)
			(layer "F.Fab")
		)
		(fp_poly
			(pts
				(xy -2.019808 -1.549908) (xy -1.257808 -1.549908) (xy -1.257808 -1.880108) (xy -2.019808 -1.880108)
			)
			(stroke
				(width 0)
				(type default)
			)
			(fill yes)
			(layer "F.Fab")
		)
		(pad "1" smd rect
			(at -1.500124 -1.249934 270)
			(size 0.2794 0.6096)
			(layers "F.Cu" "F.Mask" "F.Paste")
			(net "P12V_SSD10_R")
		)
		(pad "2" smd rect
			(at -1.500124 -0.750062 270)
			(size 0.2794 0.6096)
			(layers "F.Cu" "F.Mask" "F.Paste")
			(net "P12V_SSD10_R")
		)
		(pad "3" smd rect
			(at -1.500124 -0.249936 270)
			(size 0.2794 0.6096)
			(layers "F.Cu" "F.Mask" "F.Paste")
			(net "P12V_SSD10_R")
		)
		(pad "4" smd rect
			(at -1.500124 0.249936 270)
			(size 0.2794 0.6096)
			(layers "F.Cu" "F.Mask" "F.Paste")
			(net "P12V_SSD10_R")
		)
		(pad "5" smd rect
			(at -1.500124 0.750062 270)
			(size 0.2794 0.6096)
			(layers "F.Cu" "F.Mask" "F.Paste")
			(net "P12V_SSD10_R")
		)
		(pad "6" smd rect
			(at -1.500124 1.249934 270)
			(size 0.2794 0.6096)
			(layers "F.Cu" "F.Mask" "F.Paste")
			(net "GND")
		)
		(pad "7" smd rect
			(at 1.500124 1.249934 270)
			(size 0.2794 0.6096)
			(layers "F.Cu" "F.Mask" "F.Paste")
			(net "P12V_SSD10_SS")
		)
		(pad "8" smd rect
			(at 1.500124 0.750062 270)
			(size 0.2794 0.6096)
			(layers "F.Cu" "F.Mask" "F.Paste")
			(net "PWRGD_P12V_SSD10")
		)
		(pad "9" smd rect
			(at 1.500124 0.249936 270)
			(size 0.2794 0.6096)
			(layers "F.Cu" "F.Mask" "F.Paste")
			(net "P12V_SSD10_OCP")
		)
		(pad "10" smd rect
			(at 1.500124 -0.249936 270)
			(size 0.2794 0.6096)
			(layers "F.Cu" "F.Mask" "F.Paste")
			(net "P5V_AUX")
		)
		(pad "11" smd rect
			(at 1.500124 -0.750062 270)
			(size 0.2794 0.6096)
			(layers "F.Cu" "F.Mask" "F.Paste")
			(net "SSD10_PWR_EN_R")
		)
		(pad "12" smd rect
			(at 1.500124 -1.249934 270)
			(size 0.2794 0.6096)
			(layers "F.Cu" "F.Mask" "F.Paste")
			(net "P12V_AUX")
		)
		(pad "13" smd rect
			(at 0 0)
			(size 1.9812 2.7178)
			(layers "F.Cu" "F.Mask" "F.Paste")
			(net "P12V_AUX")
		)
		(zone
			(layer "F.Cu")
			(hatch none 0.5)
			(connect_pads
				(clearance 0)
			)
			(min_thickness 0.25)
			(keepout
				(tracks not_allowed)
				(vias allowed)
				(pads allowed)
				(copperpour not_allowed)
				(footprints allowed)
			)
			(placement
				(enabled no)
				(sheetname "")
			)
			(fill
				(thermal_gap 0.5)
				(thermal_bridge_width 0.5)
				(island_removal_mode 0)
			)
			(polygon
				(pts
					(xy 307.989986 -55.9435) (xy 307.989986 -55.8165) (xy 307.989986 -52.8447) (xy 307.989986 -52.844192)
					(xy 305.703986 -52.844192) (xy 305.703986 -52.8447) (xy 305.703986 -52.9717) (xy 305.703986 -54.3941)
					(xy 305.805586 -54.3941) (xy 305.805586 -52.9717) (xy 307.888386 -52.9717) (xy 307.888386 -55.8165)
					(xy 305.805586 -55.8165) (xy 305.805586 -54.4195) (xy 305.703986 -54.4195) (xy 305.703986 -55.8165)
					(xy 305.703986 -55.9435) (xy 305.703986 -55.944008) (xy 307.989986 -55.944008)
				)
			)
		)
	)
	(footprint ""
		(layer "F.Cu")
		(at 59.771788 -24.807418)
		(property "Reference" "R417"
			(at 0 0 0)
			(layer "F.SilkS")
			(hide yes)
			(effects
				(font
					(size 1.27 1.27)
				)
			)
		)
		(property "Value" ""
			(at 0 0 0)
			(layer "F.Fab")
			(effects
				(font
					(size 1.27 1.27)
				)
			)
		)
		(duplicate_pad_numbers_are_jumpers no)
		(fp_line
			(start -0.7874 -0.4064)
			(end 0.7874 -0.4064)
			(stroke
				(width 0.1524)
				(type default)
			)
			(layer "F.SilkS")
		)
		(fp_line
			(start -0.7874 0.4064)
			(end -0.7874 -0.4064)
			(stroke
				(width 0.1524)
				(type default)
			)
			(layer "F.SilkS")
		)
		(fp_line
			(start 0.7874 -0.4064)
			(end 0.7874 0.4064)
			(stroke
				(width 0.1524)
				(type default)
			)
			(layer "F.SilkS")
		)
		(fp_line
			(start 0.7874 0.4064)
			(end -0.7874 0.4064)
			(stroke
				(width 0.1524)
				(type default)
			)
			(layer "F.SilkS")
		)
		(fp_line
			(start -0.67945 -0.305054)
			(end -0.12065 -0.305054)
			(stroke
				(width 0.1)
				(type default)
			)
			(layer "F.Fab")
		)
		(fp_line
			(start -0.67945 0.3048)
			(end -0.67945 -0.305054)
			(stroke
				(width 0.1)
				(type default)
			)
			(layer "F.Fab")
		)
		(fp_line
			(start -0.12065 -0.305054)
			(end -0.12065 -0.2794)
			(stroke
				(width 0.1)
				(type default)
			)
			(layer "F.Fab")
		)
		(fp_line
			(start -0.12065 -0.2794)
			(end 0.12065 -0.2794)
			(stroke
				(width 0.1)
				(type default)
			)
			(layer "F.Fab")
		)
		(fp_line
			(start -0.12065 0.2794)
			(end -0.12065 0.3048)
			(stroke
				(width 0.1)
				(type default)
			)
			(layer "F.Fab")
		)
		(fp_line
			(start -0.12065 0.3048)
			(end -0.67945 0.3048)
			(stroke
				(width 0.1)
				(type default)
			)
			(layer "F.Fab")
		)
		(fp_line
			(start 0.120396 0.2794)
			(end -0.12065 0.2794)
			(stroke
				(width 0.1)
				(type default)
			)
			(layer "F.Fab")
		)
		(fp_line
			(start 0.120396 0.3048)
			(end 0.120396 0.2794)
			(stroke
				(width 0.1)
				(type default)
			)
			(layer "F.Fab")
		)
		(fp_line
			(start 0.12065 -0.3048)
			(end 0.67945 -0.3048)
			(stroke
				(width 0.1)
				(type default)
			)
			(layer "F.Fab")
		)
		(fp_line
			(start 0.12065 -0.2794)
			(end 0.12065 -0.3048)
			(stroke
				(width 0.1)
				(type default)
			)
			(layer "F.Fab")
		)
		(fp_line
			(start 0.67945 -0.3048)
			(end 0.67945 0.3048)
			(stroke
				(width 0.1)
				(type default)
			)
			(layer "F.Fab")
		)
		(fp_line
			(start 0.67945 0.3048)
			(end 0.120396 0.3048)
			(stroke
				(width 0.1)
				(type default)
			)
			(layer "F.Fab")
		)
		(pad "1" smd circle
			(at -0.40005 0)
			(size 0 0)
			(layers "F.Cu" "F.Mask" "F.Paste")
			(net "P3V3_SSD2")
		)
		(pad "2" smd circle
			(at 0.40005 0)
			(size 0 0)
			(layers "F.Cu" "F.Mask" "F.Paste")
			(net "PU_CLKREQ2")
		)
	)
	(footprint ""
		(layer "F.Cu")
		(at 362.65485 -303.698402 90)
		(property "Reference" "PC185"
			(at 0 0 90)
			(layer "F.SilkS")
			(hide yes)
			(effects
				(font
					(size 1.27 1.27)
				)
			)
		)
		(property "Value" ""
			(at 0 0 90)
			(layer "F.Fab")
			(effects
				(font
					(size 1.27 1.27)
				)
			)
		)
		(duplicate_pad_numbers_are_jumpers no)
		(fp_line
			(start -4.53898 -2.150618)
			(end -4.539742 2.152142)
			(stroke
				(width 0.1524)
				(type default)
			)
			(layer "F.SilkS")
		)
		(fp_line
			(start -4.69138 -2.150618)
			(end -4.692396 2.161032)
			(stroke
				(width 0.1524)
				(type default)
			)
			(layer "F.SilkS")
		)
		(fp_line
			(start -4.84378 -2.150618)
			(end -4.53898 -2.150618)
			(stroke
				(width 0.1524)
				(type default)
			)
			(layer "F.SilkS")
		)
		(fp_line
			(start -4.84378 -2.150618)
			(end -4.842256 2.163064)
			(stroke
				(width 0.1524)
				(type default)
			)
			(layer "F.SilkS")
		)
		(fp_line
			(start 4.53898 -2.15011)
			(end 4.53898 2.15011)
			(stroke
				(width 0.1524)
				(type default)
			)
			(layer "F.SilkS")
		)
		(fp_line
			(start -4.53898 -2.15011)
			(end 4.53898 -2.15011)
			(stroke
				(width 0.1524)
				(type default)
			)
			(layer "F.SilkS")
		)
		(fp_line
			(start 4.53898 2.15011)
			(end -4.53898 2.15011)
			(stroke
				(width 0.1524)
				(type default)
			)
			(layer "F.SilkS")
		)
		(fp_line
			(start -4.53898 2.15011)
			(end -4.53898 -2.15011)
			(stroke
				(width 0.1524)
				(type default)
			)
			(layer "F.SilkS")
		)
		(fp_line
			(start -4.83108 2.150364)
			(end -4.447794 2.149348)
			(stroke
				(width 0.1524)
				(type default)
			)
			(layer "F.SilkS")
		)
		(fp_line
			(start 3.64998 -2.15011)
			(end 3.64998 2.15011)
			(stroke
				(width 0.1)
				(type default)
			)
			(layer "F.Fab")
		)
		(fp_line
			(start -3.64998 -2.15011)
			(end 3.64998 -2.15011)
			(stroke
				(width 0.1)
				(type default)
			)
			(layer "F.Fab")
		)
		(fp_line
			(start 3.64998 2.15011)
			(end -3.64998 2.15011)
			(stroke
				(width 0.1)
				(type default)
			)
			(layer "F.Fab")
		)
		(fp_line
			(start -3.64998 2.15011)
			(end -3.64998 -2.15011)
			(stroke
				(width 0.1)
				(type default)
			)
			(layer "F.Fab")
		)
		(fp_text user "-"
			(at 4.736084 0.091694 90)
			(unlocked yes)
			(layer "F.SilkS")
			(effects
				(font
					(size 1.905 1.4224)
					(thickness 0.1524)
				)
				(justify left)
			)
		)
		(fp_text user "+"
			(at -4.86156 2.689606 90)
			(unlocked yes)
			(layer "F.SilkS")
			(effects
				(font
					(size 1.905 1.4224)
					(thickness 0.1524)
				)
				(justify left)
			)
		)
		(fp_text user "+"
			(at -6.214872 -0.337058 90)
			(unlocked yes)
			(layer "F.Fab")
			(effects
				(font
					(size 1.905 1.4224)
					(thickness 0.1524)
				)
				(justify left)
			)
		)
		(fp_text user "-"
			(at 4.313174 -0.094488 90)
			(unlocked yes)
			(layer "F.Fab")
			(effects
				(font
					(size 1.905 1.4224)
					(thickness 0.1524)
				)
				(justify left)
			)
		)
		(pad "1" smd rect
			(at -3.199892 0 90)
			(size 2.413 2.8194)
			(layers "F.Cu" "F.Mask" "F.Paste")
			(net "P0V8_PEX3")
		)
		(pad "2" smd rect
			(at 3.199892 0 90)
			(size 2.413 2.8194)
			(layers "F.Cu" "F.Mask" "F.Paste")
			(net "GND")
		)
	)
	(footprint ""
		(layer "F.Cu")
		(at 312.21934 -143.504666 180)
		(property "Reference" "C437"
			(at 0 0 180)
			(layer "F.SilkS")
			(hide yes)
			(effects
				(font
					(size 1.27 1.27)
				)
			)
		)
		(property "Value" ""
			(at 0 0 180)
			(layer "F.Fab")
			(effects
				(font
					(size 1.27 1.27)
				)
			)
		)
		(duplicate_pad_numbers_are_jumpers no)
		(fp_line
			(start 0.299974 0.150114)
			(end -0.299974 0.150114)
			(stroke
				(width 0.1)
				(type default)
			)
			(layer "F.Fab")
		)
		(fp_line
			(start 0.299974 -0.150114)
			(end 0.299974 0.150114)
			(stroke
				(width 0.1)
				(type default)
			)
			(layer "F.Fab")
		)
		(fp_line
			(start -0.299974 0.150114)
			(end -0.299974 -0.150114)
			(stroke
				(width 0.1)
				(type default)
			)
			(layer "F.Fab")
		)
		(fp_line
			(start -0.299974 -0.150114)
			(end 0.299974 -0.150114)
			(stroke
				(width 0.1)
				(type default)
			)
			(layer "F.Fab")
		)
		(pad "1" smd rect
			(at -0.2667 0 180)
			(size 0.3048 0.381)
			(layers "F.Cu" "F.Mask" "F.Paste")
			(net "P5E_PEX2_STN0_TX_DP<8>")
		)
		(pad "2" smd rect
			(at 0.2667 0 180)
			(size 0.3048 0.381)
			(layers "F.Cu" "F.Mask" "F.Paste")
			(net "P5E_PEX2_STN0_TX_C_DP<8>")
		)
	)
)
